(kicad_pcb
	(version 20260206)
	(generator "pcbnew")
	(generator_version "10.0")
	(general
		(thickness 1.6)
		(legacy_teardrops no)
	)
	(paper "A4")
	(title_block
		(title "Bryce Canyon_R.DPB_16317-1_OCP.brd")
		(comment 1 "Bryce Canyon / footprints 132-139 of 2099")
	)
	(layers
		(0 "F.Cu" signal "TOP")
		(4 "In1.Cu" signal "L2GND")
		(6 "In2.Cu" signal "L3")
		(8 "In3.Cu" signal "L4VCC")
		(10 "In4.Cu" signal "L5VCC")
		(12 "In5.Cu" signal "L6")
		(14 "In6.Cu" signal "L7GND")
		(2 "B.Cu" signal "BOTTOM")
		(9 "F.Adhes" user "F.Adhesive")
		(11 "B.Adhes" user "B.Adhesive")
		(13 "F.Paste" user "Package Geometry/Pastemask Top")
		(15 "B.Paste" user "Package Geometry/Pastemask Bottom")
		(5 "F.SilkS" user "Ref Des/Silkscreen Top")
		(7 "B.SilkS" user "Ref Des/Silkscreen Bottom")
		(1 "F.Mask" user "Board Geometry/Soldermask Top")
		(3 "B.Mask" user "Board Geometry/Soldermask Bottom")
		(17 "Dwgs.User" user "User.Drawings")
		(19 "Cmts.User" user "User.Comments")
		(21 "Eco1.User" user "User.Eco1")
		(23 "Eco2.User" user "User.Eco2")
		(25 "Edge.Cuts" user "Board Geometry/Outline")
		(27 "Margin" user)
		(31 "F.CrtYd" user "Package Geometry/Place Bound Top")
		(29 "B.CrtYd" user "Package Geometry/Place Bound Bottom")
		(35 "F.Fab" user "Ref Des/Assembly Top")
		(33 "B.Fab" user "Ref Des/Assembly Bottom")
	)
	(footprint ""
		(layer "F.Cu")
		(at 251.948696 -226.35591 -90)
		(property "Reference" "C30"
			(at 0 0 270)
			(layer "F.SilkS")
			(hide yes)
			(effects
				(font
					(size 1.27 1.27)
				)
			)
		)
		(property "Value" "SCD1U16V2KX-3GP"
			(at 1.1811 -2.7051 270)
			(unlocked yes)
			(layer "F.Fab")
			(hide yes)
			(effects
				(font
					(size 1.016 1.016)
					(thickness 0.1524)
				)
			)
		)
		(property "Device Type" "C402H22"
			(at 1.1811 -4.2291 270)
			(unlocked yes)
			(layer "F.Fab")
			(hide yes)
			(effects
				(font
					(size 1.016 1.016)
					(thickness 0.1524)
				)
			)
		)
		(duplicate_pad_numbers_are_jumpers no)
		(fp_rect
			(start -0.4318 0.9525)
			(end 0.4318 -0.9525)
			(stroke
				(width 0)
				(type default)
			)
			(fill no)
			(layer "F.CrtYd")
		)
		(fp_rect
			(start -0.4318 0.9525)
			(end 0.4318 -0.9525)
			(stroke
				(width 0)
				(type default)
			)
			(fill no)
			(layer "F.Fab")
		)
		(pad "1" smd custom
			(at 0 -0.4445 270)
			(size 0.1524 0.1524)
			(layers "F.Cu" "F.Mask" "F.Paste")
			(net "P3V3_SENSE")
			(options
				(clearance outline)
				(anchor circle)
			)
			(primitives
				(gr_poly
					(pts
						(arc
							(start 0.3048 -0.2032)
							(mid 0.275042 -0.275042)
							(end 0.2032 -0.3048)
						)
						(arc
							(start -0.2032 -0.3048)
							(mid -0.275042 -0.275042)
							(end -0.3048 -0.2032)
						)
						(arc
							(start -0.3048 0.2032)
							(mid -0.275042 0.275042)
							(end -0.2032 0.3048)
						)
						(arc
							(start 0.2032 0.3048)
							(mid 0.275042 0.275042)
							(end 0.3048 0.2032)
						)
					)
					(width 0)
					(fill yes)
				)
			)
		)
		(pad "2" smd custom
			(at 0 0.4445 270)
			(size 0.1524 0.1524)
			(layers "F.Cu" "F.Mask" "F.Paste")
			(net "GND")
			(options
				(clearance outline)
				(anchor circle)
			)
			(primitives
				(gr_poly
					(pts
						(arc
							(start 0.3048 -0.2032)
							(mid 0.275042 -0.275042)
							(end 0.2032 -0.3048)
						)
						(arc
							(start -0.2032 -0.3048)
							(mid -0.275042 -0.275042)
							(end -0.3048 -0.2032)
						)
						(arc
							(start -0.3048 0.2032)
							(mid -0.275042 0.275042)
							(end -0.2032 0.3048)
						)
						(arc
							(start 0.2032 0.3048)
							(mid 0.275042 0.275042)
							(end 0.3048 0.2032)
						)
					)
					(width 0)
					(fill yes)
				)
			)
		)
	)
	(footprint ""
		(layer "F.Cu")
		(at 52.649882 -111.842804 90)
		(property "Reference" "C643"
			(at 0 0 90)
			(layer "F.SilkS")
			(hide yes)
			(effects
				(font
					(size 1.27 1.27)
				)
			)
		)
		(property "Value" "SCD1U16V2KX-3GP"
			(at 1.1811 -2.7051 90)
			(unlocked yes)
			(layer "F.Fab")
			(hide yes)
			(effects
				(font
					(size 1.016 1.016)
					(thickness 0.1524)
				)
			)
		)
		(property "Device Type" "C402H22"
			(at 1.1811 -4.2291 90)
			(unlocked yes)
			(layer "F.Fab")
			(hide yes)
			(effects
				(font
					(size 1.016 1.016)
					(thickness 0.1524)
				)
			)
		)
		(duplicate_pad_numbers_are_jumpers no)
		(fp_rect
			(start -0.4318 0.9525)
			(end 0.4318 -0.9525)
			(stroke
				(width 0)
				(type default)
			)
			(fill no)
			(layer "F.CrtYd")
		)
		(fp_rect
			(start -0.4318 0.9525)
			(end 0.4318 -0.9525)
			(stroke
				(width 0)
				(type default)
			)
			(fill no)
			(layer "F.Fab")
		)
		(pad "1" smd custom
			(at 0 -0.4445 90)
			(size 0.1524 0.1524)
			(layers "F.Cu" "F.Mask" "F.Paste")
			(net "P5V_B_2_VBST_RC")
			(options
				(clearance outline)
				(anchor circle)
			)
			(primitives
				(gr_poly
					(pts
						(arc
							(start 0.3048 -0.2032)
							(mid 0.275042 -0.275042)
							(end 0.2032 -0.3048)
						)
						(arc
							(start -0.2032 -0.3048)
							(mid -0.275042 -0.275042)
							(end -0.3048 -0.2032)
						)
						(arc
							(start -0.3048 0.2032)
							(mid -0.275042 0.275042)
							(end -0.2032 0.3048)
						)
						(arc
							(start 0.2032 0.3048)
							(mid 0.275042 0.275042)
							(end 0.3048 0.2032)
						)
					)
					(width 0)
					(fill yes)
				)
			)
		)
		(pad "2" smd custom
			(at 0 0.4445 90)
			(size 0.1524 0.1524)
			(layers "F.Cu" "F.Mask" "F.Paste")
			(net "P5V_B_2_LL")
			(options
				(clearance outline)
				(anchor circle)
			)
			(primitives
				(gr_poly
					(pts
						(arc
							(start 0.3048 -0.2032)
							(mid 0.275042 -0.275042)
							(end 0.2032 -0.3048)
						)
						(arc
							(start -0.2032 -0.3048)
							(mid -0.275042 -0.275042)
							(end -0.3048 -0.2032)
						)
						(arc
							(start -0.3048 0.2032)
							(mid -0.275042 0.275042)
							(end -0.2032 0.3048)
						)
						(arc
							(start 0.2032 0.3048)
							(mid 0.275042 0.275042)
							(end 0.3048 0.2032)
						)
					)
					(width 0)
					(fill yes)
				)
			)
		)
	)
	(footprint ""
		(layer "F.Cu")
		(at 400.05 -131.826 180)
		(property "Reference" "R544"
			(at 0 0 180)
			(layer "F.SilkS")
			(hide yes)
			(effects
				(font
					(size 1.27 1.27)
				)
			)
		)
		(property "Value" "4K7R2J-2-GP"
			(at 0.064008 -3.993896 180)
			(unlocked yes)
			(layer "F.Fab")
			(hide yes)
			(effects
				(font
					(size 1.016 1.016)
					(thickness 0.1524)
				)
			)
		)
		(property "Device Type" "R402H16"
			(at 0.064008 -5.517896 180)
			(unlocked yes)
			(layer "F.Fab")
			(hide yes)
			(effects
				(font
					(size 1.016 1.016)
					(thickness 0.1524)
				)
			)
		)
		(duplicate_pad_numbers_are_jumpers no)
		(fp_line
			(start 0.508 -0.9398)
			(end -0.508 -0.9398)
			(stroke
				(width 0.1524)
				(type default)
			)
			(layer "F.SilkS")
		)
		(fp_line
			(start -0.508 -0.9398)
			(end -0.508 0.9398)
			(stroke
				(width 0.1524)
				(type default)
			)
			(layer "F.SilkS")
		)
		(fp_rect
			(start -0.508 0.9398)
			(end 0.508 -0.9398)
			(stroke
				(width 0)
				(type default)
			)
			(fill no)
			(layer "F.CrtYd")
		)
		(fp_rect
			(start -0.508 0.9398)
			(end 0.508 -0.9398)
			(stroke
				(width 0)
				(type default)
			)
			(fill no)
			(layer "F.Fab")
		)
		(pad "1" smd custom
			(at 0 -0.4445 180)
			(size 0.1397 0.1397)
			(layers "F.Cu" "F.Mask" "F.Paste")
			(net "P12V_B")
			(options
				(clearance outline)
				(anchor circle)
			)
			(primitives
				(gr_poly
					(pts
						(arc
							(start -0.1778 -0.2794)
							(mid -0.249642 -0.249642)
							(end -0.2794 -0.1778)
						)
						(arc
							(start -0.2794 0.1778)
							(mid -0.249642 0.249642)
							(end -0.1778 0.2794)
						)
						(arc
							(start 0.1778 0.2794)
							(mid 0.249642 0.249642)
							(end 0.2794 0.1778)
						)
						(arc
							(start 0.2794 -0.1778)
							(mid 0.249642 -0.249642)
							(end 0.1778 -0.2794)
						)
					)
					(width 0)
					(fill yes)
				)
			)
		)
		(pad "2" smd custom
			(at 0 0.4445 180)
			(size 0.1397 0.1397)
			(layers "F.Cu" "F.Mask" "F.Paste")
			(net "SW_HDD_R20")
			(options
				(clearance outline)
				(anchor circle)
			)
			(primitives
				(gr_poly
					(pts
						(arc
							(start -0.1778 -0.2794)
							(mid -0.249642 -0.249642)
							(end -0.2794 -0.1778)
						)
						(arc
							(start -0.2794 0.1778)
							(mid -0.249642 0.249642)
							(end -0.1778 0.2794)
						)
						(arc
							(start 0.1778 0.2794)
							(mid 0.249642 0.249642)
							(end 0.2794 0.1778)
						)
						(arc
							(start 0.2794 -0.1778)
							(mid 0.249642 -0.249642)
							(end 0.1778 -0.2794)
						)
					)
					(width 0)
					(fill yes)
				)
			)
		)
	)
	(footprint ""
		(layer "F.Cu")
		(at 418.239702 -248.750074 -90)
		(property "Reference" "VIA20"
			(at 0 0 270)
			(layer "F.SilkS")
			(hide yes)
			(effects
				(font
					(size 1.27 1.27)
				)
			)
		)
		(property "Value" "100OHM-8L-2D36MM-L16-GP"
			(at -3.4036 -0.4572 270)
			(unlocked yes)
			(layer "F.Fab")
			(hide yes)
			(effects
				(font
					(size 1.016 1.016)
					(thickness 0.1524)
				)
			)
		)
		(property "Device Type" "VIA-PCIE-4P-427097"
			(at -3.4036 -1.9812 270)
			(unlocked yes)
			(layer "F.Fab")
			(hide yes)
			(effects
				(font
					(size 1.016 1.016)
					(thickness 0.1524)
				)
			)
		)
		(duplicate_pad_numbers_are_jumpers no)
		(fp_rect
			(start -2.1336 0.4826)
			(end 2.1336 -0.4826)
			(stroke
				(width 0)
				(type default)
			)
			(fill no)
			(layer "F.CrtYd")
		)
		(fp_rect
			(start -2.1336 0.4826)
			(end 2.1336 -0.4826)
			(stroke
				(width 0)
				(type default)
			)
			(fill no)
			(layer "F.Fab")
		)
		(pad "1" thru_hole circle
			(at -1.651 0 270)
			(size 0.508 0.508)
			(drill 0.254)
			(layers "*.Cu" "*.Mask")
			(remove_unused_layers no)
			(net "GND")
			(clearance 0.2286)
			(thermal_gap 0.2286)
		)
		(pad "2" thru_hole circle
			(at -0.635 0 270)
			(size 0.508 0.508)
			(drill 0.254)
			(layers "*.Cu" "*.Mask")
			(remove_unused_layers no)
			(net "PHY_DRV_B_TO_SCC_B_9_DP")
			(clearance 0.2286)
			(thermal_gap 0.2286)
		)
		(pad "3" thru_hole circle
			(at 0.635 0 270)
			(size 0.508 0.508)
			(drill 0.254)
			(layers "*.Cu" "*.Mask")
			(remove_unused_layers no)
			(net "PHY_DRV_B_TO_SCC_B_9_DN")
			(clearance 0.2286)
			(thermal_gap 0.2286)
		)
		(pad "4" thru_hole circle
			(at 1.651 0 270)
			(size 0.508 0.508)
			(drill 0.254)
			(layers "*.Cu" "*.Mask")
			(remove_unused_layers no)
			(net "GND")
			(clearance 0.2286)
			(thermal_gap 0.2286)
		)
	)
	(footprint ""
		(layer "F.Cu")
		(at 221.29496 -161.90976)
		(property "Reference" "R56"
			(at 0 0 0)
			(layer "F.SilkS")
			(hide yes)
			(effects
				(font
					(size 1.27 1.27)
				)
			)
		)
		(property "Value" "0R2J-2-GP"
			(at 0.064008 -3.993896 0)
			(unlocked yes)
			(layer "F.Fab")
			(hide yes)
			(effects
				(font
					(size 1.016 1.016)
					(thickness 0.1524)
				)
			)
		)
		(property "Device Type" "R402H16"
			(at 0.064008 -5.517896 0)
			(unlocked yes)
			(layer "F.Fab")
			(hide yes)
			(effects
				(font
					(size 1.016 1.016)
					(thickness 0.1524)
				)
			)
		)
		(duplicate_pad_numbers_are_jumpers no)
		(fp_line
			(start -0.508 -0.9398)
			(end -0.508 0.9398)
			(stroke
				(width 0.1524)
				(type default)
			)
			(layer "F.SilkS")
		)
		(fp_line
			(start 0.508 -0.9398)
			(end -0.508 -0.9398)
			(stroke
				(width 0.1524)
				(type default)
			)
			(layer "F.SilkS")
		)
		(fp_rect
			(start -0.508 0.9398)
			(end 0.508 -0.9398)
			(stroke
				(width 0)
				(type default)
			)
			(fill no)
			(layer "F.CrtYd")
		)
		(fp_rect
			(start -0.508 0.9398)
			(end 0.508 -0.9398)
			(stroke
				(width 0)
				(type default)
			)
			(fill no)
			(layer "F.Fab")
		)
		(pad "1" smd custom
			(at 0 -0.4445)
			(size 0.1397 0.1397)
			(layers "F.Cu" "F.Mask" "F.Paste")
			(net "IO_EXP6_INT_N")
			(options
				(clearance outline)
				(anchor circle)
			)
			(primitives
				(gr_poly
					(pts
						(arc
							(start -0.1778 -0.2794)
							(mid -0.249642 -0.249642)
							(end -0.2794 -0.1778)
						)
						(arc
							(start -0.2794 0.1778)
							(mid -0.249642 0.249642)
							(end -0.1778 0.2794)
						)
						(arc
							(start 0.1778 0.2794)
							(mid 0.249642 0.249642)
							(end 0.2794 0.1778)
						)
						(arc
							(start 0.2794 -0.1778)
							(mid 0.249642 -0.249642)
							(end 0.1778 -0.2794)
						)
					)
					(width 0)
					(fill yes)
				)
			)
		)
		(pad "2" smd custom
			(at 0 0.4445)
			(size 0.1397 0.1397)
			(layers "F.Cu" "F.Mask" "F.Paste")
			(net "DRIVE_INSERT_ALERT_B_N")
			(options
				(clearance outline)
				(anchor circle)
			)
			(primitives
				(gr_poly
					(pts
						(arc
							(start -0.1778 -0.2794)
							(mid -0.249642 -0.249642)
							(end -0.2794 -0.1778)
						)
						(arc
							(start -0.2794 0.1778)
							(mid -0.249642 0.249642)
							(end -0.1778 0.2794)
						)
						(arc
							(start 0.1778 0.2794)
							(mid 0.249642 0.249642)
							(end 0.2794 0.1778)
						)
						(arc
							(start 0.2794 -0.1778)
							(mid 0.249642 -0.249642)
							(end 0.1778 -0.2794)
						)
					)
					(width 0)
					(fill yes)
				)
			)
		)
	)
	(footprint ""
		(layer "F.Cu")
		(at 55.88 -19.177)
		(property "Reference" "R656"
			(at 0 0 0)
			(layer "F.SilkS")
			(hide yes)
			(effects
				(font
					(size 1.27 1.27)
				)
			)
		)
		(property "Value" "0R2J-2-GP"
			(at 0.064008 -3.993896 0)
			(unlocked yes)
			(layer "F.Fab")
			(hide yes)
			(effects
				(font
					(size 1.016 1.016)
					(thickness 0.1524)
				)
			)
		)
		(property "Device Type" "R402H16"
			(at 0.064008 -5.517896 0)
			(unlocked yes)
			(layer "F.Fab")
			(hide yes)
			(effects
				(font
					(size 1.016 1.016)
					(thickness 0.1524)
				)
			)
		)
		(duplicate_pad_numbers_are_jumpers no)
		(fp_line
			(start -0.508 -0.9398)
			(end -0.508 0.9398)
			(stroke
				(width 0.1524)
				(type default)
			)
			(layer "F.SilkS")
		)
		(fp_line
			(start 0.508 -0.9398)
			(end -0.508 -0.9398)
			(stroke
				(width 0.1524)
				(type default)
			)
			(layer "F.SilkS")
		)
		(fp_rect
			(start -0.508 0.9398)
			(end 0.508 -0.9398)
			(stroke
				(width 0)
				(type default)
			)
			(fill no)
			(layer "F.CrtYd")
		)
		(fp_rect
			(start -0.508 0.9398)
			(end 0.508 -0.9398)
			(stroke
				(width 0)
				(type default)
			)
			(fill no)
			(layer "F.Fab")
		)
		(pad "1" smd custom
			(at 0 -0.4445)
			(size 0.1397 0.1397)
			(layers "F.Cu" "F.Mask" "F.Paste")
			(net "DRIVE_B_25_PWR")
			(options
				(clearance outline)
				(anchor circle)
			)
			(primitives
				(gr_poly
					(pts
						(arc
							(start -0.1778 -0.2794)
							(mid -0.249642 -0.249642)
							(end -0.2794 -0.1778)
						)
						(arc
							(start -0.2794 0.1778)
							(mid -0.249642 0.249642)
							(end -0.1778 0.2794)
						)
						(arc
							(start 0.1778 0.2794)
							(mid 0.249642 0.249642)
							(end 0.2794 0.1778)
						)
						(arc
							(start 0.2794 -0.1778)
							(mid 0.249642 -0.249642)
							(end 0.1778 -0.2794)
						)
					)
					(width 0)
					(fill yes)
				)
			)
		)
		(pad "2" smd custom
			(at 0 0.4445)
			(size 0.1397 0.1397)
			(layers "F.Cu" "F.Mask" "F.Paste")
			(net "SW_PWR_R_HDD25")
			(options
				(clearance outline)
				(anchor circle)
			)
			(primitives
				(gr_poly
					(pts
						(arc
							(start -0.1778 -0.2794)
							(mid -0.249642 -0.249642)
							(end -0.2794 -0.1778)
						)
						(arc
							(start -0.2794 0.1778)
							(mid -0.249642 0.249642)
							(end -0.1778 0.2794)
						)
						(arc
							(start 0.1778 0.2794)
							(mid 0.249642 0.249642)
							(end 0.2794 0.1778)
						)
						(arc
							(start 0.2794 -0.1778)
							(mid 0.249642 -0.249642)
							(end 0.1778 -0.2794)
						)
					)
					(width 0)
					(fill yes)
				)
			)
		)
	)
	(footprint ""
		(layer "F.Cu")
		(at 186.7281 -377.5583 -90)
		(property "Reference" "R967"
			(at 0 0 270)
			(layer "F.SilkS")
			(hide yes)
			(effects
				(font
					(size 1.27 1.27)
				)
			)
		)
		(property "Value" "1KR5F-1-GP"
			(at 0 -8.9535 270)
			(unlocked yes)
			(layer "F.Fab")
			(hide yes)
			(effects
				(font
					(size 1.27 1.016)
					(thickness 0.1524)
				)
			)
		)
		(property "Device Type" "R805H24"
			(at 0 -10.6299 270)
			(unlocked yes)
			(layer "F.Fab")
			(hide yes)
			(effects
				(font
					(size 1.27 1.016)
					(thickness 0.1524)
				)
			)
		)
		(duplicate_pad_numbers_are_jumpers no)
		(fp_line
			(start -0.889 1.7018)
			(end 0.889 1.7018)
			(stroke
				(width 0.1524)
				(type default)
			)
			(layer "F.SilkS")
		)
		(fp_line
			(start 0.889 1.7018)
			(end 0.889 -0.508)
			(stroke
				(width 0.1524)
				(type default)
			)
			(layer "F.SilkS")
		)
		(fp_line
			(start -0.889 0.0762)
			(end -0.889 1.7018)
			(stroke
				(width 0.1524)
				(type default)
			)
			(layer "F.SilkS")
		)
		(fp_line
			(start -0.889 -1.7018)
			(end -0.889 0.2794)
			(stroke
				(width 0.1524)
				(type default)
			)
			(layer "F.SilkS")
		)
		(fp_line
			(start 0.889 -1.7018)
			(end 0.889 -0.381)
			(stroke
				(width 0.1524)
				(type default)
			)
			(layer "F.SilkS")
		)
		(fp_line
			(start 0.889 -1.7018)
			(end -0.889 -1.7018)
			(stroke
				(width 0.1524)
				(type default)
			)
			(layer "F.SilkS")
		)
		(fp_poly
			(pts
				(xy 0.9652 -1.778) (xy 0.9652 1.778) (xy -0.9652 1.778) (xy -0.9652 -1.778)
			)
			(stroke
				(width 0)
				(type default)
			)
			(fill no)
			(layer "F.CrtYd")
		)
		(fp_rect
			(start -0.9652 1.778)
			(end 0.9652 -1.778)
			(stroke
				(width 0)
				(type default)
			)
			(fill no)
			(layer "F.Fab")
		)
		(pad "1" smd rect
			(at 0 -0.9652 270)
			(size 1.397 1.143)
			(layers "F.Cu" "F.Mask" "F.Paste")
			(net "FAN_YELLOW_1")
		)
		(pad "2" smd rect
			(at 0 0.9652 270)
			(size 1.397 1.143)
			(layers "F.Cu" "F.Mask" "F.Paste")
			(net "FAN_LED_YELLOW_1")
		)
	)
	(footprint ""
		(layer "F.Cu")
		(at 172.593 -246.634 90)
		(property "Reference" "R248"
			(at 0 0 90)
			(layer "F.SilkS")
			(hide yes)
			(effects
				(font
					(size 1.27 1.27)
				)
			)
		)
		(property "Value" "4K7R2J-2-GP"
			(at 0.064008 -3.993896 90)
			(unlocked yes)
			(layer "F.Fab")
			(hide yes)
			(effects
				(font
					(size 1.016 1.016)
					(thickness 0.1524)
				)
			)
		)
		(property "Device Type" "R402H16"
			(at 0.064008 -5.517896 90)
			(unlocked yes)
			(layer "F.Fab")
			(hide yes)
			(effects
				(font
					(size 1.016 1.016)
					(thickness 0.1524)
				)
			)
		)
		(duplicate_pad_numbers_are_jumpers no)
		(fp_line
			(start 0.508 -0.9398)
			(end -0.508 -0.9398)
			(stroke
				(width 0.1524)
				(type default)
			)
			(layer "F.SilkS")
		)
		(fp_line
			(start -0.508 -0.9398)
			(end -0.508 0.9398)
			(stroke
				(width 0.1524)
				(type default)
			)
			(layer "F.SilkS")
		)
		(fp_rect
			(start -0.508 0.9398)
			(end 0.508 -0.9398)
			(stroke
				(width 0)
				(type default)
			)
			(fill no)
			(layer "F.CrtYd")
		)
		(fp_rect
			(start -0.508 0.9398)
			(end 0.508 -0.9398)
			(stroke
				(width 0)
				(type default)
			)
			(fill no)
			(layer "F.Fab")
		)
		(pad "1" smd custom
			(at 0 -0.4445 90)
			(size 0.1397 0.1397)
			(layers "F.Cu" "F.Mask" "F.Paste")
			(net "P12V_B")
			(options
				(clearance outline)
				(anchor circle)
			)
			(primitives
				(gr_poly
					(pts
						(arc
							(start -0.1778 -0.2794)
							(mid -0.249642 -0.249642)
							(end -0.2794 -0.1778)
						)
						(arc
							(start -0.2794 0.1778)
							(mid -0.249642 0.249642)
							(end -0.1778 0.2794)
						)
						(arc
							(start 0.1778 0.2794)
							(mid 0.249642 0.249642)
							(end 0.2794 0.1778)
						)
						(arc
							(start 0.2794 -0.1778)
							(mid 0.249642 -0.249642)
							(end 0.1778 -0.2794)
						)
					)
					(width 0)
					(fill yes)
				)
			)
		)
		(pad "2" smd custom
			(at 0 0.4445 90)
			(size 0.1397 0.1397)
			(layers "F.Cu" "F.Mask" "F.Paste")
			(net "SW_HDD_R5")
			(options
				(clearance outline)
				(anchor circle)
			)
			(primitives
				(gr_poly
					(pts
						(arc
							(start -0.1778 -0.2794)
							(mid -0.249642 -0.249642)
							(end -0.2794 -0.1778)
						)
						(arc
							(start -0.2794 0.1778)
							(mid -0.249642 0.249642)
							(end -0.1778 0.2794)
						)
						(arc
							(start 0.1778 0.2794)
							(mid 0.249642 0.249642)
							(end 0.2794 0.1778)
						)
						(arc
							(start 0.2794 -0.1778)
							(mid 0.249642 -0.249642)
							(end 0.1778 -0.2794)
						)
					)
					(width 0)
					(fill yes)
				)
			)
		)
	)
)
